(kicad_pcb
	(version 20260206)
	(generator "pcbnew")
	(generator_version "10.0")
	(general
		(thickness 1.6)
		(legacy_teardrops no)
	)
	(paper "A4")
	(title_block
		(title "pdpb — Lightning_PDPB_BRD.brd")
		(comment 1 "Lightning (Wiwynn / Facebook NVMe JBOF) / footprints 444-450 of 1140")
	)
	(layers
		(0 "F.Cu" signal "TOP")
		(4 "In1.Cu" signal "L2GND")
		(6 "In2.Cu" signal "L3")
		(8 "In3.Cu" signal "L4VCC")
		(10 "In4.Cu" signal "L5VCC")
		(12 "In5.Cu" signal "L6")
		(14 "In6.Cu" signal "L7GND")
		(2 "B.Cu" signal "BOTTOM")
		(9 "F.Adhes" user "F.Adhesive")
		(11 "B.Adhes" user "B.Adhesive")
		(13 "F.Paste" user "Package Geometry/Pastemask Top")
		(15 "B.Paste" user "Package Geometry/Pastemask Bottom")
		(5 "F.SilkS" user "Ref Des/Silkscreen Top")
		(7 "B.SilkS" user "Ref Des/Silkscreen Bottom")
		(1 "F.Mask" user "Board Geometry/Soldermask Top")
		(3 "B.Mask" user "Board Geometry/Soldermask Bottom")
		(17 "Dwgs.User" user "User.Drawings")
		(19 "Cmts.User" user "User.Comments")
		(21 "Eco1.User" user "User.Eco1")
		(23 "Eco2.User" user "User.Eco2")
		(25 "Edge.Cuts" user "Board Geometry/Outline")
		(27 "Margin" user)
		(31 "F.CrtYd" user "Package Geometry/Place Bound Top")
		(29 "B.CrtYd" user "Package Geometry/Place Bound Bottom")
		(35 "F.Fab" user "Ref Des/Assembly Top")
		(33 "B.Fab" user "Ref Des/Assembly Bottom")
	)
	(footprint ""
		(layer "F.Cu")
		(at 31.0896 -290.6522 180)
		(property "Reference" "SR1106"
			(at 0 0 180)
			(layer "F.SilkS")
			(hide yes)
			(effects
				(font
					(size 1.27 1.27)
				)
			)
		)
		(property "Value" "4K7R2F-GP"
			(at 0.064008 -3.993896 180)
			(unlocked yes)
			(layer "F.Fab")
			(hide yes)
			(effects
				(font
					(size 1.016 1.016)
					(thickness 0.1524)
				)
			)
		)
		(property "Device Type" "R402H16"
			(at 0.064008 -5.517896 180)
			(unlocked yes)
			(layer "F.Fab")
			(hide yes)
			(effects
				(font
					(size 1.016 1.016)
					(thickness 0.1524)
				)
			)
		)
		(duplicate_pad_numbers_are_jumpers no)
		(fp_line
			(start 0.508 -0.9398)
			(end -0.508 -0.9398)
			(stroke
				(width 0.1524)
				(type default)
			)
			(layer "F.SilkS")
		)
		(fp_line
			(start -0.508 -0.9398)
			(end -0.508 0.9398)
			(stroke
				(width 0.1524)
				(type default)
			)
			(layer "F.SilkS")
		)
		(fp_rect
			(start -0.508 0.9398)
			(end 0.508 -0.9398)
			(stroke
				(width 0)
				(type default)
			)
			(fill no)
			(layer "F.CrtYd")
		)
		(fp_rect
			(start -0.508 0.9398)
			(end 0.508 -0.9398)
			(stroke
				(width 0)
				(type default)
			)
			(fill no)
			(layer "F.Fab")
		)
		(pad "1" smd custom
			(at 0 -0.4445 180)
			(size 0.1397 0.1397)
			(layers "F.Cu" "F.Mask" "F.Paste")
			(net "DUALPORTEN#7")
			(options
				(clearance outline)
				(anchor circle)
			)
			(primitives
				(gr_poly
					(pts
						(arc
							(start -0.1778 -0.2794)
							(mid -0.249642 -0.249642)
							(end -0.2794 -0.1778)
						)
						(arc
							(start -0.2794 0.1778)
							(mid -0.249642 0.249642)
							(end -0.1778 0.2794)
						)
						(arc
							(start 0.1778 0.2794)
							(mid 0.249642 0.249642)
							(end 0.2794 0.1778)
						)
						(arc
							(start 0.2794 -0.1778)
							(mid 0.249642 -0.249642)
							(end 0.1778 -0.2794)
						)
					)
					(width 0)
					(fill yes)
				)
			)
		)
		(pad "2" smd custom
			(at 0 0.4445 180)
			(size 0.1397 0.1397)
			(layers "F.Cu" "F.Mask" "F.Paste")
			(net "GND")
			(options
				(clearance outline)
				(anchor circle)
			)
			(primitives
				(gr_poly
					(pts
						(arc
							(start -0.1778 -0.2794)
							(mid -0.249642 -0.249642)
							(end -0.2794 -0.1778)
						)
						(arc
							(start -0.2794 0.1778)
							(mid -0.249642 0.249642)
							(end -0.1778 0.2794)
						)
						(arc
							(start 0.1778 0.2794)
							(mid 0.249642 0.249642)
							(end 0.2794 0.1778)
						)
						(arc
							(start 0.2794 -0.1778)
							(mid 0.249642 -0.249642)
							(end 0.1778 -0.2794)
						)
					)
					(width 0)
					(fill yes)
				)
			)
		)
	)
	(footprint ""
		(layer "F.Cu")
		(at 31.6992 -492.5314 -90)
		(property "Reference" "R398"
			(at 0 0 270)
			(layer "F.SilkS")
			(hide yes)
			(effects
				(font
					(size 1.27 1.27)
				)
			)
		)
		(property "Value" "0R2J-2-GP"
			(at 0.064008 -3.993896 270)
			(unlocked yes)
			(layer "F.Fab")
			(hide yes)
			(effects
				(font
					(size 1.016 1.016)
					(thickness 0.1524)
				)
			)
		)
		(property "Device Type" "R402H16"
			(at 0.064008 -5.517896 270)
			(unlocked yes)
			(layer "F.Fab")
			(hide yes)
			(effects
				(font
					(size 1.016 1.016)
					(thickness 0.1524)
				)
			)
		)
		(duplicate_pad_numbers_are_jumpers no)
		(fp_line
			(start -0.508 -0.9398)
			(end -0.508 0.9398)
			(stroke
				(width 0.1524)
				(type default)
			)
			(layer "F.SilkS")
		)
		(fp_line
			(start 0.508 -0.9398)
			(end -0.508 -0.9398)
			(stroke
				(width 0.1524)
				(type default)
			)
			(layer "F.SilkS")
		)
		(fp_rect
			(start -0.508 0.9398)
			(end 0.508 -0.9398)
			(stroke
				(width 0)
				(type default)
			)
			(fill no)
			(layer "F.CrtYd")
		)
		(fp_rect
			(start -0.508 0.9398)
			(end 0.508 -0.9398)
			(stroke
				(width 0)
				(type default)
			)
			(fill no)
			(layer "F.Fab")
		)
		(pad "1" smd custom
			(at 0 -0.4445 270)
			(size 0.1397 0.1397)
			(layers "F.Cu" "F.Mask" "F.Paste")
			(net "SDA_DR5_R")
			(options
				(clearance outline)
				(anchor circle)
			)
			(primitives
				(gr_poly
					(pts
						(arc
							(start -0.1778 -0.2794)
							(mid -0.249642 -0.249642)
							(end -0.2794 -0.1778)
						)
						(arc
							(start -0.2794 0.1778)
							(mid -0.249642 0.249642)
							(end -0.1778 0.2794)
						)
						(arc
							(start 0.1778 0.2794)
							(mid 0.249642 0.249642)
							(end 0.2794 0.1778)
						)
						(arc
							(start 0.2794 -0.1778)
							(mid 0.249642 -0.249642)
							(end 0.1778 -0.2794)
						)
					)
					(width 0)
					(fill yes)
				)
			)
		)
		(pad "2" smd custom
			(at 0 0.4445 270)
			(size 0.1397 0.1397)
			(layers "F.Cu" "F.Mask" "F.Paste")
			(net "SDA_DR5")
			(options
				(clearance outline)
				(anchor circle)
			)
			(primitives
				(gr_poly
					(pts
						(arc
							(start -0.1778 -0.2794)
							(mid -0.249642 -0.249642)
							(end -0.2794 -0.1778)
						)
						(arc
							(start -0.2794 0.1778)
							(mid -0.249642 0.249642)
							(end -0.1778 0.2794)
						)
						(arc
							(start 0.1778 0.2794)
							(mid 0.249642 0.249642)
							(end 0.2794 0.1778)
						)
						(arc
							(start 0.2794 -0.1778)
							(mid 0.249642 -0.249642)
							(end 0.1778 -0.2794)
						)
					)
					(width 0)
					(fill yes)
				)
			)
		)
	)
	(footprint ""
		(layer "F.Cu")
		(at 70.739 -357.505 -90)
		(property "Reference" "SR1051"
			(at 0 0 270)
			(layer "F.SilkS")
			(hide yes)
			(effects
				(font
					(size 1.27 1.27)
				)
			)
		)
		(property "Value" "4K7R2F-GP"
			(at 0.064008 -3.993896 270)
			(unlocked yes)
			(layer "F.Fab")
			(hide yes)
			(effects
				(font
					(size 1.016 1.016)
					(thickness 0.1524)
				)
			)
		)
		(property "Device Type" "R402H16"
			(at 0.064008 -5.517896 270)
			(unlocked yes)
			(layer "F.Fab")
			(hide yes)
			(effects
				(font
					(size 1.016 1.016)
					(thickness 0.1524)
				)
			)
		)
		(duplicate_pad_numbers_are_jumpers no)
		(fp_line
			(start -0.508 -0.9398)
			(end -0.508 0.9398)
			(stroke
				(width 0.1524)
				(type default)
			)
			(layer "F.SilkS")
		)
		(fp_line
			(start 0.508 -0.9398)
			(end -0.508 -0.9398)
			(stroke
				(width 0.1524)
				(type default)
			)
			(layer "F.SilkS")
		)
		(fp_rect
			(start -0.508 0.9398)
			(end 0.508 -0.9398)
			(stroke
				(width 0)
				(type default)
			)
			(fill no)
			(layer "F.CrtYd")
		)
		(fp_rect
			(start -0.508 0.9398)
			(end 0.508 -0.9398)
			(stroke
				(width 0)
				(type default)
			)
			(fill no)
			(layer "F.Fab")
		)
		(pad "1" smd custom
			(at 0 -0.4445 270)
			(size 0.1397 0.1397)
			(layers "F.Cu" "F.Mask" "F.Paste")
			(net "I2C_SW_EU17_ADDRESS_A2")
			(options
				(clearance outline)
				(anchor circle)
			)
			(primitives
				(gr_poly
					(pts
						(arc
							(start -0.1778 -0.2794)
							(mid -0.249642 -0.249642)
							(end -0.2794 -0.1778)
						)
						(arc
							(start -0.2794 0.1778)
							(mid -0.249642 0.249642)
							(end -0.1778 0.2794)
						)
						(arc
							(start 0.1778 0.2794)
							(mid 0.249642 0.249642)
							(end 0.2794 0.1778)
						)
						(arc
							(start 0.2794 -0.1778)
							(mid 0.249642 -0.249642)
							(end 0.1778 -0.2794)
						)
					)
					(width 0)
					(fill yes)
				)
			)
		)
		(pad "2" smd custom
			(at 0 0.4445 270)
			(size 0.1397 0.1397)
			(layers "F.Cu" "F.Mask" "F.Paste")
			(net "GND")
			(options
				(clearance outline)
				(anchor circle)
			)
			(primitives
				(gr_poly
					(pts
						(arc
							(start -0.1778 -0.2794)
							(mid -0.249642 -0.249642)
							(end -0.2794 -0.1778)
						)
						(arc
							(start -0.2794 0.1778)
							(mid -0.249642 0.249642)
							(end -0.1778 0.2794)
						)
						(arc
							(start 0.1778 0.2794)
							(mid 0.249642 0.249642)
							(end 0.2794 0.1778)
						)
						(arc
							(start 0.2794 -0.1778)
							(mid 0.249642 -0.249642)
							(end 0.1778 -0.2794)
						)
					)
					(width 0)
					(fill yes)
				)
			)
		)
	)
	(footprint ""
		(layer "F.Cu")
		(at 37.6936 -208.8134)
		(property "Reference" "Q20"
			(at 0 0 0)
			(layer "F.SilkS")
			(hide yes)
			(effects
				(font
					(size 1.27 1.27)
				)
			)
		)
		(property "Value" "2N7002A-7-GP"
			(at 0.127 -8.9662 0)
			(unlocked yes)
			(layer "F.Fab")
			(hide yes)
			(effects
				(font
					(size 1.016 1.016)
					(thickness 0.1524)
				)
			)
		)
		(property "Device Type" "SOT23DGS2D4H48"
			(at 0.127 -10.4902 0)
			(unlocked yes)
			(layer "F.Fab")
			(hide yes)
			(effects
				(font
					(size 1.016 1.016)
					(thickness 0.1524)
				)
			)
		)
		(duplicate_pad_numbers_are_jumpers no)
		(fp_line
			(start -1.651 -1.778)
			(end -1.651 1.778)
			(stroke
				(width 0.1524)
				(type default)
			)
			(layer "F.SilkS")
		)
		(fp_line
			(start -1.651 1.778)
			(end 1.651 1.778)
			(stroke
				(width 0.1524)
				(type default)
			)
			(layer "F.SilkS")
		)
		(fp_line
			(start 1.651 -1.778)
			(end -1.651 -1.778)
			(stroke
				(width 0.1524)
				(type default)
			)
			(layer "F.SilkS")
		)
		(fp_line
			(start 1.651 1.778)
			(end 1.651 -1.778)
			(stroke
				(width 0.1524)
				(type default)
			)
			(layer "F.SilkS")
		)
		(fp_poly
			(pts
				(xy -1.778 1.8796) (xy -1.778 -1.8796) (xy 1.778 -1.8796) (xy 1.778 1.8796)
			)
			(stroke
				(width 0)
				(type default)
			)
			(fill no)
			(layer "F.CrtYd")
		)
		(fp_poly
			(pts
				(xy -1.778 1.8796) (xy -1.778 -1.8796) (xy 1.778 -1.8796) (xy 1.778 1.8796)
			)
			(stroke
				(width 0)
				(type default)
			)
			(fill no)
			(layer "F.Fab")
		)
		(pad "D" smd custom
			(at 0 -0.9525)
			(size 0.1905 0.1905)
			(layers "F.Cu" "F.Mask" "F.Paste")
			(net "SW_SSD12_R")
			(options
				(clearance outline)
				(anchor circle)
			)
			(primitives
				(gr_poly
					(pts
						(arc
							(start -0.1778 0.5715)
							(mid -0.321484 0.511984)
							(end -0.381 0.3683)
						)
						(arc
							(start -0.381 -0.3683)
							(mid -0.321484 -0.511984)
							(end -0.1778 -0.5715)
						)
						(arc
							(start 0.1778 -0.5715)
							(mid 0.321484 -0.511984)
							(end 0.381 -0.3683)
						)
						(arc
							(start 0.381 0.3683)
							(mid 0.321484 0.511984)
							(end 0.1778 0.5715)
						)
					)
					(width 0)
					(fill yes)
				)
			)
		)
		(pad "G" smd custom
			(at -0.98425 0.9525)
			(size 0.1905 0.1905)
			(layers "F.Cu" "F.Mask" "F.Paste")
			(net "SSD12_PWREN")
			(options
				(clearance outline)
				(anchor circle)
			)
			(primitives
				(gr_poly
					(pts
						(arc
							(start -0.1778 0.5715)
							(mid -0.321484 0.511984)
							(end -0.381 0.3683)
						)
						(arc
							(start -0.381 -0.3683)
							(mid -0.321484 -0.511984)
							(end -0.1778 -0.5715)
						)
						(arc
							(start 0.1778 -0.5715)
							(mid 0.321484 -0.511984)
							(end 0.381 -0.3683)
						)
						(arc
							(start 0.381 0.3683)
							(mid 0.321484 0.511984)
							(end 0.1778 0.5715)
						)
					)
					(width 0)
					(fill yes)
				)
			)
		)
		(pad "S" smd custom
			(at 0.98425 0.9525)
			(size 0.1905 0.1905)
			(layers "F.Cu" "F.Mask" "F.Paste")
			(net "GND")
			(options
				(clearance outline)
				(anchor circle)
			)
			(primitives
				(gr_poly
					(pts
						(arc
							(start -0.1778 0.5715)
							(mid -0.321484 0.511984)
							(end -0.381 0.3683)
						)
						(arc
							(start -0.381 -0.3683)
							(mid -0.321484 -0.511984)
							(end -0.1778 -0.5715)
						)
						(arc
							(start 0.1778 -0.5715)
							(mid 0.321484 -0.511984)
							(end 0.381 -0.3683)
						)
						(arc
							(start 0.381 0.3683)
							(mid 0.321484 0.511984)
							(end 0.1778 0.5715)
						)
					)
					(width 0)
					(fill yes)
				)
			)
		)
	)
	(footprint ""
		(layer "F.Cu")
		(at 39.83355 -410.01315 -90)
		(property "Reference" "R9845"
			(at 0 0 270)
			(layer "F.SilkS")
			(hide yes)
			(effects
				(font
					(size 1.27 1.27)
				)
			)
		)
		(property "Value" "1KR2J-1-GP"
			(at 0.064008 -3.993896 270)
			(unlocked yes)
			(layer "F.Fab")
			(hide yes)
			(effects
				(font
					(size 1.016 1.016)
					(thickness 0.1524)
				)
			)
		)
		(property "Device Type" "R402H16"
			(at 0.064008 -5.517896 270)
			(unlocked yes)
			(layer "F.Fab")
			(hide yes)
			(effects
				(font
					(size 1.016 1.016)
					(thickness 0.1524)
				)
			)
		)
		(duplicate_pad_numbers_are_jumpers no)
		(fp_line
			(start -0.508 -0.9398)
			(end -0.508 0.9398)
			(stroke
				(width 0.1524)
				(type default)
			)
			(layer "F.SilkS")
		)
		(fp_line
			(start 0.508 -0.9398)
			(end -0.508 -0.9398)
			(stroke
				(width 0.1524)
				(type default)
			)
			(layer "F.SilkS")
		)
		(fp_rect
			(start -0.508 0.9398)
			(end 0.508 -0.9398)
			(stroke
				(width 0)
				(type default)
			)
			(fill no)
			(layer "F.CrtYd")
		)
		(fp_rect
			(start -0.508 0.9398)
			(end 0.508 -0.9398)
			(stroke
				(width 0)
				(type default)
			)
			(fill no)
			(layer "F.Fab")
		)
		(pad "1" smd custom
			(at 0 -0.4445 270)
			(size 0.1397 0.1397)
			(layers "F.Cu" "F.Mask" "F.Paste")
			(net "SSD10_PWREN")
			(options
				(clearance outline)
				(anchor circle)
			)
			(primitives
				(gr_poly
					(pts
						(arc
							(start -0.1778 -0.2794)
							(mid -0.249642 -0.249642)
							(end -0.2794 -0.1778)
						)
						(arc
							(start -0.2794 0.1778)
							(mid -0.249642 0.249642)
							(end -0.1778 0.2794)
						)
						(arc
							(start 0.1778 0.2794)
							(mid 0.249642 0.249642)
							(end 0.2794 0.1778)
						)
						(arc
							(start 0.2794 -0.1778)
							(mid 0.249642 -0.249642)
							(end 0.1778 -0.2794)
						)
					)
					(width 0)
					(fill yes)
				)
			)
		)
		(pad "2" smd custom
			(at 0 0.4445 270)
			(size 0.1397 0.1397)
			(layers "F.Cu" "F.Mask" "F.Paste")
			(net "SSD10_PWREN_R")
			(options
				(clearance outline)
				(anchor circle)
			)
			(primitives
				(gr_poly
					(pts
						(arc
							(start -0.1778 -0.2794)
							(mid -0.249642 -0.249642)
							(end -0.2794 -0.1778)
						)
						(arc
							(start -0.2794 0.1778)
							(mid -0.249642 0.249642)
							(end -0.1778 0.2794)
						)
						(arc
							(start 0.1778 0.2794)
							(mid 0.249642 0.249642)
							(end 0.2794 0.1778)
						)
						(arc
							(start 0.2794 -0.1778)
							(mid 0.249642 -0.249642)
							(end 0.1778 -0.2794)
						)
					)
					(width 0)
					(fill yes)
				)
			)
		)
	)
	(footprint ""
		(layer "F.Cu")
		(at 35.56 -297.18 180)
		(property "Reference" "PC1245"
			(at 0 0 180)
			(layer "F.SilkS")
			(hide yes)
			(effects
				(font
					(size 1.27 1.27)
				)
			)
		)
		(property "Value" "SC22U25V6KX-GP-U"
			(at -2.860802 -5.279644 180)
			(unlocked yes)
			(layer "F.Fab")
			(hide yes)
			(effects
				(font
					(size 1.016 1.016)
					(thickness 0.1524)
				)
			)
		)
		(property "Device Type" "C1206-TO0D3H75"
			(at -2.860802 -6.803644 180)
			(unlocked yes)
			(layer "F.Fab")
			(hide yes)
			(effects
				(font
					(size 1.016 1.016)
					(thickness 0.1524)
				)
			)
		)
		(duplicate_pad_numbers_are_jumpers no)
		(fp_line
			(start 1.3081 2.3749)
			(end -1.3081 2.3749)
			(stroke
				(width 0.1524)
				(type default)
			)
			(layer "F.SilkS")
		)
		(fp_line
			(start 1.3081 -2.3749)
			(end 1.3081 2.3749)
			(stroke
				(width 0.1524)
				(type default)
			)
			(layer "F.SilkS")
		)
		(fp_line
			(start -1.3081 2.3749)
			(end -1.3081 -2.3749)
			(stroke
				(width 0.1524)
				(type default)
			)
			(layer "F.SilkS")
		)
		(fp_line
			(start -1.3081 -2.3749)
			(end 1.3081 -2.3749)
			(stroke
				(width 0.1524)
				(type default)
			)
			(layer "F.SilkS")
		)
		(fp_rect
			(start -0.8001 1.6002)
			(end 0.8001 -1.6002)
			(stroke
				(width 0)
				(type default)
			)
			(fill no)
			(layer "F.CrtYd")
		)
		(fp_poly
			(pts
				(xy -1.5621 2.4511) (xy -1.5621 1.6002) (xy 0.8001 1.6002) (xy 0.8001 -1.6002) (xy -0.8001 -1.6002)
				(xy -0.8001 1.5875) (xy -1.5621 1.5875) (xy -1.5621 -2.4511) (xy 1.5621 -2.4511) (xy 1.5621 2.4511)
			)
			(stroke
				(width 0)
				(type default)
			)
			(fill no)
			(layer "F.CrtYd")
		)
		(fp_rect
			(start -1.5621 2.4511)
			(end 1.5621 -2.4511)
			(stroke
				(width 0)
				(type default)
			)
			(fill no)
			(layer "F.Fab")
		)
		(pad "1" smd rect
			(at 0 -1.392936 180)
			(size 2.1082 1.4478)
			(layers "F.Cu" "F.Mask" "F.Paste")
			(net "P12V_SSD7")
		)
		(pad "2" smd rect
			(at 0 1.392936 180)
			(size 2.1082 1.4478)
			(layers "F.Cu" "F.Mask" "F.Paste")
			(net "GND")
		)
	)
	(footprint ""
		(layer "F.Cu")
		(at 219.329 -243.580158 90)
		(property "Reference" "SR1125"
			(at 0 0 90)
			(layer "F.SilkS")
			(hide yes)
			(effects
				(font
					(size 1.27 1.27)
				)
			)
		)
		(property "Value" "4K7R2F-GP"
			(at 0.064008 -3.993896 90)
			(unlocked yes)
			(layer "F.Fab")
			(hide yes)
			(effects
				(font
					(size 1.016 1.016)
					(thickness 0.1524)
				)
			)
		)
		(property "Device Type" "R402H16"
			(at 0.064008 -5.517896 90)
			(unlocked yes)
			(layer "F.Fab")
			(hide yes)
			(effects
				(font
					(size 1.016 1.016)
					(thickness 0.1524)
				)
			)
		)
		(duplicate_pad_numbers_are_jumpers no)
		(fp_line
			(start 0.508 -0.9398)
			(end -0.508 -0.9398)
			(stroke
				(width 0.1524)
				(type default)
			)
			(layer "F.SilkS")
		)
		(fp_line
			(start -0.508 -0.9398)
			(end -0.508 0.9398)
			(stroke
				(width 0.1524)
				(type default)
			)
			(layer "F.SilkS")
		)
		(fp_rect
			(start -0.508 0.9398)
			(end 0.508 -0.9398)
			(stroke
				(width 0)
				(type default)
			)
			(fill no)
			(layer "F.CrtYd")
		)
		(fp_rect
			(start -0.508 0.9398)
			(end 0.508 -0.9398)
			(stroke
				(width 0)
				(type default)
			)
			(fill no)
			(layer "F.Fab")
		)
		(pad "1" smd custom
			(at 0 -0.4445 90)
			(size 0.1397 0.1397)
			(layers "F.Cu" "F.Mask" "F.Paste")
			(net "P3V3")
			(options
				(clearance outline)
				(anchor circle)
			)
			(primitives
				(gr_poly
					(pts
						(arc
							(start -0.1778 -0.2794)
							(mid -0.249642 -0.249642)
							(end -0.2794 -0.1778)
						)
						(arc
							(start -0.2794 0.1778)
							(mid -0.249642 0.249642)
							(end -0.1778 0.2794)
						)
						(arc
							(start 0.1778 0.2794)
							(mid 0.249642 0.249642)
							(end 0.2794 0.1778)
						)
						(arc
							(start 0.2794 -0.1778)
							(mid 0.249642 -0.249642)
							(end 0.1778 -0.2794)
						)
					)
					(width 0)
					(fill yes)
				)
			)
		)
		(pad "2" smd custom
			(at 0 0.4445 90)
			(size 0.1397 0.1397)
			(layers "F.Cu" "F.Mask" "F.Paste")
			(net "SSD2_CLK0_OE_MOS_N")
			(options
				(clearance outline)
				(anchor circle)
			)
			(primitives
				(gr_poly
					(pts
						(arc
							(start -0.1778 -0.2794)
							(mid -0.249642 -0.249642)
							(end -0.2794 -0.1778)
						)
						(arc
							(start -0.2794 0.1778)
							(mid -0.249642 0.249642)
							(end -0.1778 0.2794)
						)
						(arc
							(start 0.1778 0.2794)
							(mid 0.249642 0.249642)
							(end 0.2794 0.1778)
						)
						(arc
							(start 0.2794 -0.1778)
							(mid 0.249642 -0.249642)
							(end 0.1778 -0.2794)
						)
					)
					(width 0)
					(fill yes)
				)
			)
		)
	)
)
